# SCM (Grand Teton) — schematic netlist excerpt (pin names and nets, part order shuffled) for the footprints in the layout excerpt that follows; sources: Cadence DE-HDL packaged netlist, KiCad conversion of 12092022_DA0F0TMDCD0_F0T_Management_Board_D_brd_V3_OCP.brd

C107  Q_CAP  0.1UF 25V 10% X7R  pkg 0402  page 16 : A = P1V2_AUX ; B = GND
C5  Q_CAP  1UF 25V 10% X6S  pkg C0402  page 20 : A = P1V2_AUX ; B = GND

(kicad_pcb
	(version 20260206)
	(generator "pcbnew")
	(generator_version "10.0")
	(general
		(thickness 1.6)
		(legacy_teardrops no)
	)
	(paper "A4")
	(title_block
		(title "12092022_DA0F0TMDCD0_F0T_Management_Board_D_brd_V3_OCP.brd")
		(comment 1 "Grand Teton / footprints 817-818 of 1440")
	)
	(layers
		(0 "F.Cu" signal "TOP")
		(4 "In1.Cu" signal "GND")
		(6 "In2.Cu" signal "IN1")
		(8 "In3.Cu" signal "GND1")
		(10 "In4.Cu" signal "IN2")
		(12 "In5.Cu" signal "VCC")
		(14 "In6.Cu" signal "VCC1")
		(16 "In7.Cu" signal "IN3")
		(18 "In8.Cu" signal "GND2")
		(20 "In9.Cu" signal "IN4")
		(22 "In10.Cu" signal "GND3")
		(2 "B.Cu" signal "BOTTOM")
		(9 "F.Adhes" user "F.Adhesive")
		(11 "B.Adhes" user "B.Adhesive")
		(13 "F.Paste" user "Package Geometry/Pastemask Top")
		(15 "B.Paste" user "Package Geometry/Pastemask Bottom")
		(5 "F.SilkS" user "Ref Des/Silkscreen Top")
		(7 "B.SilkS" user "Ref Des/Silkscreen Bottom")
		(1 "F.Mask" user "Board Geometry/Soldermask Top")
		(3 "B.Mask" user "Board Geometry/Soldermask Bottom")
		(17 "Dwgs.User" user "User.Drawings")
		(19 "Cmts.User" user "User.Comments")
		(21 "Eco1.User" user "User.Eco1")
		(23 "Eco2.User" user "User.Eco2")
		(25 "Edge.Cuts" user "Board Geometry/Outline")
		(27 "Margin" user)
		(31 "F.CrtYd" user "Package Geometry/Place Bound Top")
		(29 "B.CrtYd" user "Package Geometry/Place Bound Bottom")
		(35 "F.Fab" user "Ref Des/Assembly Top")
		(33 "B.Fab" user "Ref Des/Assembly Bottom")
	)
	(footprint ""
		(layer "B.Cu")
		(at 53.719476 -47.913036 90)
		(property "Reference" "C107"
			(at 0 0 90)
			(layer "B.SilkS")
			(hide yes)
			(effects
				(font
					(size 1.27 1.27)
				)
				(justify mirror)
			)
		)
		(property "Value" ""
			(at 0 0 90)
			(layer "B.Fab")
			(effects
				(font
					(size 1.27 1.27)
				)
				(justify mirror)
			)
		)
		(duplicate_pad_numbers_are_jumpers no)
		(fp_line
			(start 0.7874 -0.4064)
			(end -0.7874 -0.4064)
			(stroke
				(width 0.1524)
				(type default)
			)
			(layer "B.SilkS")
		)
		(fp_line
			(start -0.7874 -0.4064)
			(end -0.7874 0.4064)
			(stroke
				(width 0.1524)
				(type default)
			)
			(layer "B.SilkS")
		)
		(fp_line
			(start 0.7874 0.4064)
			(end 0.7874 -0.4064)
			(stroke
				(width 0.1524)
				(type default)
			)
			(layer "B.SilkS")
		)
		(fp_line
			(start -0.7874 0.4064)
			(end 0.7874 0.4064)
			(stroke
				(width 0.1524)
				(type default)
			)
			(layer "B.SilkS")
		)
		(fp_line
			(start 0.67945 -0.305054)
			(end 0.12065 -0.305054)
			(stroke
				(width 0.1)
				(type default)
			)
			(layer "B.Fab")
		)
		(fp_line
			(start 0.12065 -0.305054)
			(end 0.12065 -0.2794)
			(stroke
				(width 0.1)
				(type default)
			)
			(layer "B.Fab")
		)
		(fp_line
			(start -0.12065 -0.3048)
			(end -0.67945 -0.3048)
			(stroke
				(width 0.1)
				(type default)
			)
			(layer "B.Fab")
		)
		(fp_line
			(start -0.67945 -0.3048)
			(end -0.67945 0.3048)
			(stroke
				(width 0.1)
				(type default)
			)
			(layer "B.Fab")
		)
		(fp_line
			(start 0.12065 -0.2794)
			(end -0.12065 -0.2794)
			(stroke
				(width 0.1)
				(type default)
			)
			(layer "B.Fab")
		)
		(fp_line
			(start -0.12065 -0.2794)
			(end -0.12065 -0.3048)
			(stroke
				(width 0.1)
				(type default)
			)
			(layer "B.Fab")
		)
		(fp_line
			(start 0.12065 0.2794)
			(end 0.12065 0.3048)
			(stroke
				(width 0.1)
				(type default)
			)
			(layer "B.Fab")
		)
		(fp_line
			(start -0.120396 0.2794)
			(end 0.12065 0.2794)
			(stroke
				(width 0.1)
				(type default)
			)
			(layer "B.Fab")
		)
		(fp_line
			(start 0.67945 0.3048)
			(end 0.67945 -0.305054)
			(stroke
				(width 0.1)
				(type default)
			)
			(layer "B.Fab")
		)
		(fp_line
			(start 0.12065 0.3048)
			(end 0.67945 0.3048)
			(stroke
				(width 0.1)
				(type default)
			)
			(layer "B.Fab")
		)
		(fp_line
			(start -0.120396 0.3048)
			(end -0.120396 0.2794)
			(stroke
				(width 0.1)
				(type default)
			)
			(layer "B.Fab")
		)
		(fp_line
			(start -0.67945 0.3048)
			(end -0.120396 0.3048)
			(stroke
				(width 0.1)
				(type default)
			)
			(layer "B.Fab")
		)
		(pad "1" smd circle
			(at 0.40005 0 270)
			(size 0 0)
			(layers "B.Cu" "B.Mask" "B.Paste")
			(net "P1V2_AUX")
		)
		(pad "2" smd circle
			(at -0.40005 0 270)
			(size 0 0)
			(layers "B.Cu" "B.Mask" "B.Paste")
			(net "GND")
		)
	)
	(footprint ""
		(layer "B.Cu")
		(at 71.676768 -51.63185 90)
		(property "Reference" "C5"
			(at 0 0 90)
			(layer "B.SilkS")
			(hide yes)
			(effects
				(font
					(size 1.27 1.27)
				)
				(justify mirror)
			)
		)
		(property "Value" ""
			(at 0 0 90)
			(layer "B.Fab")
			(effects
				(font
					(size 1.27 1.27)
				)
				(justify mirror)
			)
		)
		(duplicate_pad_numbers_are_jumpers no)
		(fp_line
			(start 0.7874 -0.4064)
			(end -0.7874 -0.4064)
			(stroke
				(width 0.1524)
				(type default)
			)
			(layer "B.SilkS")
		)
		(fp_line
			(start -0.7874 -0.4064)
			(end -0.7874 0.4064)
			(stroke
				(width 0.1524)
				(type default)
			)
			(layer "B.SilkS")
		)
		(fp_line
			(start 0.7874 0.4064)
			(end 0.7874 -0.4064)
			(stroke
				(width 0.1524)
				(type default)
			)
			(layer "B.SilkS")
		)
		(fp_line
			(start -0.7874 0.4064)
			(end 0.7874 0.4064)
			(stroke
				(width 0.1524)
				(type default)
			)
			(layer "B.SilkS")
		)
		(fp_line
			(start 0.67945 -0.305054)
			(end 0.12065 -0.305054)
			(stroke
				(width 0.1)
				(type default)
			)
			(layer "B.Fab")
		)
		(fp_line
			(start 0.12065 -0.305054)
			(end 0.12065 -0.2794)
			(stroke
				(width 0.1)
				(type default)
			)
			(layer "B.Fab")
		)
		(fp_line
			(start -0.12065 -0.3048)
			(end -0.67945 -0.3048)
			(stroke
				(width 0.1)
				(type default)
			)
			(layer "B.Fab")
		)
		(fp_line
			(start -0.67945 -0.3048)
			(end -0.67945 0.3048)
			(stroke
				(width 0.1)
				(type default)
			)
			(layer "B.Fab")
		)
		(fp_line
			(start 0.12065 -0.2794)
			(end -0.12065 -0.2794)
			(stroke
				(width 0.1)
				(type default)
			)
			(layer "B.Fab")
		)
		(fp_line
			(start -0.12065 -0.2794)
			(end -0.12065 -0.3048)
			(stroke
				(width 0.1)
				(type default)
			)
			(layer "B.Fab")
		)
		(fp_line
			(start 0.12065 0.2794)
			(end 0.12065 0.3048)
			(stroke
				(width 0.1)
				(type default)
			)
			(layer "B.Fab")
		)
		(fp_line
			(start -0.120396 0.2794)
			(end 0.12065 0.2794)
			(stroke
				(width 0.1)
				(type default)
			)
			(layer "B.Fab")
		)
		(fp_line
			(start 0.67945 0.3048)
			(end 0.67945 -0.305054)
			(stroke
				(width 0.1)
				(type default)
			)
			(layer "B.Fab")
		)
		(fp_line
			(start 0.12065 0.3048)
			(end 0.67945 0.3048)
			(stroke
				(width 0.1)
				(type default)
			)
			(layer "B.Fab")
		)
		(fp_line
			(start -0.120396 0.3048)
			(end -0.120396 0.2794)
			(stroke
				(width 0.1)
				(type default)
			)
			(layer "B.Fab")
		)
		(fp_line
			(start -0.67945 0.3048)
			(end -0.120396 0.3048)
			(stroke
				(width 0.1)
				(type default)
			)
			(layer "B.Fab")
		)
		(pad "1" smd circle
			(at 0.40005 0 270)
			(size 0 0)
			(layers "B.Cu" "B.Mask" "B.Paste")
			(net "P1V2_AUX")
		)
		(pad "2" smd circle
			(at -0.40005 0 270)
			(size 0 0)
			(layers "B.Cu" "B.Mask" "B.Paste")
			(net "GND")
		)
	)
)
